(kicad_pcb
	(version 20260206)
	(generator "pcbnew")
	(generator_version "10.0")
	(general
		(thickness 1.6)
		(legacy_teardrops no)
	)
	(paper "A4")
	(title_block
		(title "04192023_DAF0TMB3IC0_F0TG_MB_C_brd_V02_OCP.brd")
		(comment 1 "Grand Teton / footprints 1894-1901 of 8354")
	)
	(layers
		(0 "F.Cu" signal "TOP")
		(4 "In1.Cu" signal "GND")
		(6 "In2.Cu" signal "IN1")
		(8 "In3.Cu" signal "GND1")
		(10 "In4.Cu" signal "IN2")
		(12 "In5.Cu" signal "GND2")
		(14 "In6.Cu" signal "IN3")
		(16 "In7.Cu" signal "GND3")
		(18 "In8.Cu" signal "VCC")
		(20 "In9.Cu" signal "VCC1")
		(22 "In10.Cu" signal "GND4")
		(24 "In11.Cu" signal "IN4")
		(26 "In12.Cu" signal "GND5")
		(28 "In13.Cu" signal "IN5")
		(30 "In14.Cu" signal "GND6")
		(32 "In15.Cu" signal "IN6")
		(34 "In16.Cu" signal "GND7")
		(2 "B.Cu" signal "BOTTOM")
		(9 "F.Adhes" user "F.Adhesive")
		(11 "B.Adhes" user "B.Adhesive")
		(13 "F.Paste" user "Package Geometry/Pastemask Top")
		(15 "B.Paste" user "Package Geometry/Pastemask Bottom")
		(5 "F.SilkS" user "Ref Des/Silkscreen Top")
		(7 "B.SilkS" user "Ref Des/Silkscreen Bottom")
		(1 "F.Mask" user "Board Geometry/Soldermask Top")
		(3 "B.Mask" user "Board Geometry/Soldermask Bottom")
		(17 "Dwgs.User" user "User.Drawings")
		(19 "Cmts.User" user "User.Comments")
		(21 "Eco1.User" user "User.Eco1")
		(23 "Eco2.User" user "User.Eco2")
		(25 "Edge.Cuts" user "Board Geometry/Outline")
		(27 "Margin" user)
		(31 "F.CrtYd" user "Package Geometry/Place Bound Top")
		(29 "B.CrtYd" user "Package Geometry/Place Bound Bottom")
		(35 "F.Fab" user "Ref Des/Assembly Top")
		(33 "B.Fab" user "Ref Des/Assembly Bottom")
	)
	(footprint ""
		(layer "F.Cu")
		(at 208.28 -133.223 90)
		(property "Reference" "Q3"
			(at -0.741934 -3.189224 90)
			(unlocked yes)
			(layer "F.SilkS")
			(effects
				(font
					(size 0.7874 0.5842)
					(thickness 0.1524)
				)
				(justify left)
			)
		)
		(property "Value" ""
			(at 0 0 90)
			(layer "F.Fab")
			(effects
				(font
					(size 1.27 1.27)
				)
			)
		)
		(duplicate_pad_numbers_are_jumpers no)
		(fp_line
			(start 1.332738 -1.100074)
			(end 1.332738 1.100074)
			(stroke
				(width 0.1524)
				(type default)
			)
			(layer "F.SilkS")
		)
		(fp_line
			(start 0.4826 -1.100074)
			(end 1.332738 -1.100074)
			(stroke
				(width 0.1524)
				(type default)
			)
			(layer "F.SilkS")
		)
		(fp_line
			(start -0.4826 -1.100074)
			(end 0 -0.541274)
			(stroke
				(width 0.1524)
				(type default)
			)
			(layer "F.SilkS")
		)
		(fp_line
			(start -1.332738 -1.100074)
			(end -0.4826 -1.100074)
			(stroke
				(width 0.1524)
				(type default)
			)
			(layer "F.SilkS")
		)
		(fp_line
			(start 0 -0.541274)
			(end 0.4826 -1.100074)
			(stroke
				(width 0.1524)
				(type default)
			)
			(layer "F.SilkS")
		)
		(fp_line
			(start 1.332738 1.100074)
			(end -1.332738 1.100074)
			(stroke
				(width 0.1524)
				(type default)
			)
			(layer "F.SilkS")
		)
		(fp_line
			(start -1.332738 1.100074)
			(end -1.332738 -1.100074)
			(stroke
				(width 0.1524)
				(type default)
			)
			(layer "F.SilkS")
		)
		(fp_poly
			(pts
				(xy -2.699512 -0.335534) (xy -2.699512 -1.03759) (xy -1.997456 -0.686562)
			)
			(stroke
				(width 0)
				(type default)
			)
			(fill yes)
			(layer "F.SilkS")
		)
		(fp_line
			(start 0.674878 -1.100074)
			(end 0.674878 1.100074)
			(stroke
				(width 0.1)
				(type default)
			)
			(layer "F.Fab")
		)
		(fp_line
			(start -0.674878 -1.100074)
			(end 0.674878 -1.100074)
			(stroke
				(width 0.1)
				(type default)
			)
			(layer "F.Fab")
		)
		(fp_line
			(start 0.674878 1.100074)
			(end -0.674878 1.100074)
			(stroke
				(width 0.1)
				(type default)
			)
			(layer "F.Fab")
		)
		(fp_line
			(start -0.674878 1.100074)
			(end -0.674878 -1.100074)
			(stroke
				(width 0.1)
				(type default)
			)
			(layer "F.Fab")
		)
		(fp_poly
			(pts
				(xy -2.2352 -0.298958) (xy -2.2352 -1.001014) (xy -1.533144 -0.649986)
			)
			(stroke
				(width 0)
				(type default)
			)
			(fill yes)
			(layer "F.Fab")
		)
		(pad "1" smd rect
			(at -0.94996 -0.649986 180)
			(size 0.4318 0.508)
			(layers "F.Cu" "F.Mask" "F.Paste")
			(net "GND")
		)
		(pad "2" smd rect
			(at -0.94996 0 180)
			(size 0.4318 0.508)
			(layers "F.Cu" "F.Mask" "F.Paste")
			(net "SW_P3V3_EN_R")
		)
		(pad "3" smd rect
			(at -0.94996 0.649986 180)
			(size 0.4318 0.508)
			(layers "F.Cu" "F.Mask" "F.Paste")
			(net "SW_P3V3_EN_ISO")
		)
		(pad "4" smd rect
			(at 0.94996 0.649986 180)
			(size 0.4318 0.508)
			(layers "F.Cu" "F.Mask" "F.Paste")
			(net "GND")
		)
		(pad "5" smd rect
			(at 0.94996 0 180)
			(size 0.4318 0.508)
			(layers "F.Cu" "F.Mask" "F.Paste")
			(net "SW_P3V3_EN_N")
		)
		(pad "6" smd rect
			(at 0.94996 -0.649986 180)
			(size 0.4318 0.508)
			(layers "F.Cu" "F.Mask" "F.Paste")
			(net "SW_P3V3_EN_N")
		)
	)
	(footprint ""
		(layer "F.Cu")
		(at 70.307454 -147.339812 -90)
		(property "Reference" "PC153"
			(at 0 0 270)
			(layer "F.SilkS")
			(hide yes)
			(effects
				(font
					(size 1.27 1.27)
				)
			)
		)
		(property "Value" ""
			(at 0 0 270)
			(layer "F.Fab")
			(effects
				(font
					(size 1.27 1.27)
				)
			)
		)
		(duplicate_pad_numbers_are_jumpers no)
		(fp_line
			(start -0.7874 0.4064)
			(end -0.7874 -0.4064)
			(stroke
				(width 0.1524)
				(type default)
			)
			(layer "F.SilkS")
		)
		(fp_line
			(start 0.7874 0.4064)
			(end -0.7874 0.4064)
			(stroke
				(width 0.1524)
				(type default)
			)
			(layer "F.SilkS")
		)
		(fp_line
			(start -0.7874 -0.4064)
			(end 0.7874 -0.4064)
			(stroke
				(width 0.1524)
				(type default)
			)
			(layer "F.SilkS")
		)
		(fp_line
			(start 0.7874 -0.4064)
			(end 0.7874 0.4064)
			(stroke
				(width 0.1524)
				(type default)
			)
			(layer "F.SilkS")
		)
		(fp_line
			(start -0.67945 0.3048)
			(end -0.67945 -0.305054)
			(stroke
				(width 0.1)
				(type default)
			)
			(layer "F.Fab")
		)
		(fp_line
			(start -0.12065 0.3048)
			(end -0.67945 0.3048)
			(stroke
				(width 0.1)
				(type default)
			)
			(layer "F.Fab")
		)
		(fp_line
			(start 0.120396 0.3048)
			(end 0.120396 0.2794)
			(stroke
				(width 0.1)
				(type default)
			)
			(layer "F.Fab")
		)
		(fp_line
			(start 0.67945 0.3048)
			(end 0.120396 0.3048)
			(stroke
				(width 0.1)
				(type default)
			)
			(layer "F.Fab")
		)
		(fp_line
			(start -0.12065 0.2794)
			(end -0.12065 0.3048)
			(stroke
				(width 0.1)
				(type default)
			)
			(layer "F.Fab")
		)
		(fp_line
			(start 0.120396 0.2794)
			(end -0.12065 0.2794)
			(stroke
				(width 0.1)
				(type default)
			)
			(layer "F.Fab")
		)
		(fp_line
			(start -0.12065 -0.2794)
			(end 0.12065 -0.2794)
			(stroke
				(width 0.1)
				(type default)
			)
			(layer "F.Fab")
		)
		(fp_line
			(start 0.12065 -0.2794)
			(end 0.12065 -0.3048)
			(stroke
				(width 0.1)
				(type default)
			)
			(layer "F.Fab")
		)
		(fp_line
			(start 0.12065 -0.3048)
			(end 0.67945 -0.3048)
			(stroke
				(width 0.1)
				(type default)
			)
			(layer "F.Fab")
		)
		(fp_line
			(start 0.67945 -0.3048)
			(end 0.67945 0.3048)
			(stroke
				(width 0.1)
				(type default)
			)
			(layer "F.Fab")
		)
		(fp_line
			(start -0.67945 -0.305054)
			(end -0.12065 -0.305054)
			(stroke
				(width 0.1)
				(type default)
			)
			(layer "F.Fab")
		)
		(fp_line
			(start -0.12065 -0.305054)
			(end -0.12065 -0.2794)
			(stroke
				(width 0.1)
				(type default)
			)
			(layer "F.Fab")
		)
		(pad "1" smd circle
			(at -0.40005 0 270)
			(size 0 0)
			(layers "F.Cu" "F.Mask" "F.Paste")
			(net "PVDD18_S5_P1_REF")
		)
		(pad "2" smd circle
			(at 0.40005 0 270)
			(size 0 0)
			(layers "F.Cu" "F.Mask" "F.Paste")
			(net "GND")
		)
	)
	(footprint ""
		(layer "F.Cu")
		(at 25.90673 -351.578672 90)
		(property "Reference" "PC621_10"
			(at 0 0 90)
			(layer "F.SilkS")
			(hide yes)
			(effects
				(font
					(size 1.27 1.27)
				)
			)
		)
		(property "Value" ""
			(at 0 0 90)
			(layer "F.Fab")
			(effects
				(font
					(size 1.27 1.27)
				)
			)
		)
		(duplicate_pad_numbers_are_jumpers no)
		(fp_line
			(start 0.7874 -0.4064)
			(end 0.7874 0.4064)
			(stroke
				(width 0.1524)
				(type default)
			)
			(layer "F.SilkS")
		)
		(fp_line
			(start -0.7874 -0.4064)
			(end 0.7874 -0.4064)
			(stroke
				(width 0.1524)
				(type default)
			)
			(layer "F.SilkS")
		)
		(fp_line
			(start 0.7874 0.4064)
			(end -0.7874 0.4064)
			(stroke
				(width 0.1524)
				(type default)
			)
			(layer "F.SilkS")
		)
		(fp_line
			(start -0.7874 0.4064)
			(end -0.7874 -0.4064)
			(stroke
				(width 0.1524)
				(type default)
			)
			(layer "F.SilkS")
		)
		(fp_line
			(start -0.12065 -0.305054)
			(end -0.12065 -0.2794)
			(stroke
				(width 0.1)
				(type default)
			)
			(layer "F.Fab")
		)
		(fp_line
			(start -0.67945 -0.305054)
			(end -0.12065 -0.305054)
			(stroke
				(width 0.1)
				(type default)
			)
			(layer "F.Fab")
		)
		(fp_line
			(start 0.67945 -0.3048)
			(end 0.67945 0.3048)
			(stroke
				(width 0.1)
				(type default)
			)
			(layer "F.Fab")
		)
		(fp_line
			(start 0.12065 -0.3048)
			(end 0.67945 -0.3048)
			(stroke
				(width 0.1)
				(type default)
			)
			(layer "F.Fab")
		)
		(fp_line
			(start 0.12065 -0.2794)
			(end 0.12065 -0.3048)
			(stroke
				(width 0.1)
				(type default)
			)
			(layer "F.Fab")
		)
		(fp_line
			(start -0.12065 -0.2794)
			(end 0.12065 -0.2794)
			(stroke
				(width 0.1)
				(type default)
			)
			(layer "F.Fab")
		)
		(fp_line
			(start 0.120396 0.2794)
			(end -0.12065 0.2794)
			(stroke
				(width 0.1)
				(type default)
			)
			(layer "F.Fab")
		)
		(fp_line
			(start -0.12065 0.2794)
			(end -0.12065 0.3048)
			(stroke
				(width 0.1)
				(type default)
			)
			(layer "F.Fab")
		)
		(fp_line
			(start 0.67945 0.3048)
			(end 0.120396 0.3048)
			(stroke
				(width 0.1)
				(type default)
			)
			(layer "F.Fab")
		)
		(fp_line
			(start 0.120396 0.3048)
			(end 0.120396 0.2794)
			(stroke
				(width 0.1)
				(type default)
			)
			(layer "F.Fab")
		)
		(fp_line
			(start -0.12065 0.3048)
			(end -0.67945 0.3048)
			(stroke
				(width 0.1)
				(type default)
			)
			(layer "F.Fab")
		)
		(fp_line
			(start -0.67945 0.3048)
			(end -0.67945 -0.305054)
			(stroke
				(width 0.1)
				(type default)
			)
			(layer "F.Fab")
		)
		(pad "1" smd circle
			(at -0.40005 0 90)
			(size 0 0)
			(layers "F.Cu" "F.Mask" "F.Paste")
			(net "PVDDCR_CPU1_P1_VCCS")
		)
		(pad "2" smd circle
			(at 0.40005 0 90)
			(size 0 0)
			(layers "F.Cu" "F.Mask" "F.Paste")
			(net "GND")
		)
	)
	(footprint ""
		(layer "F.Cu")
		(at 68.961 -53.594 180)
		(property "Reference" "R1147"
			(at 0 0 180)
			(layer "F.SilkS")
			(hide yes)
			(effects
				(font
					(size 1.27 1.27)
				)
			)
		)
		(property "Value" ""
			(at 0 0 180)
			(layer "F.Fab")
			(effects
				(font
					(size 1.27 1.27)
				)
			)
		)
		(duplicate_pad_numbers_are_jumpers no)
		(fp_line
			(start 0.7874 0.4064)
			(end -0.7874 0.4064)
			(stroke
				(width 0.1524)
				(type default)
			)
			(layer "F.SilkS")
		)
		(fp_line
			(start 0.7874 -0.4064)
			(end 0.7874 0.4064)
			(stroke
				(width 0.1524)
				(type default)
			)
			(layer "F.SilkS")
		)
		(fp_line
			(start -0.7874 0.4064)
			(end -0.7874 -0.4064)
			(stroke
				(width 0.1524)
				(type default)
			)
			(layer "F.SilkS")
		)
		(fp_line
			(start -0.7874 -0.4064)
			(end 0.7874 -0.4064)
			(stroke
				(width 0.1524)
				(type default)
			)
			(layer "F.SilkS")
		)
		(fp_line
			(start 0.67945 0.3048)
			(end 0.120396 0.3048)
			(stroke
				(width 0.1)
				(type default)
			)
			(layer "F.Fab")
		)
		(fp_line
			(start 0.67945 -0.3048)
			(end 0.67945 0.3048)
			(stroke
				(width 0.1)
				(type default)
			)
			(layer "F.Fab")
		)
		(fp_line
			(start 0.12065 -0.2794)
			(end 0.12065 -0.3048)
			(stroke
				(width 0.1)
				(type default)
			)
			(layer "F.Fab")
		)
		(fp_line
			(start 0.12065 -0.3048)
			(end 0.67945 -0.3048)
			(stroke
				(width 0.1)
				(type default)
			)
			(layer "F.Fab")
		)
		(fp_line
			(start 0.120396 0.3048)
			(end 0.120396 0.2794)
			(stroke
				(width 0.1)
				(type default)
			)
			(layer "F.Fab")
		)
		(fp_line
			(start 0.120396 0.2794)
			(end -0.12065 0.2794)
			(stroke
				(width 0.1)
				(type default)
			)
			(layer "F.Fab")
		)
		(fp_line
			(start -0.12065 0.3048)
			(end -0.67945 0.3048)
			(stroke
				(width 0.1)
				(type default)
			)
			(layer "F.Fab")
		)
		(fp_line
			(start -0.12065 0.2794)
			(end -0.12065 0.3048)
			(stroke
				(width 0.1)
				(type default)
			)
			(layer "F.Fab")
		)
		(fp_line
			(start -0.12065 -0.2794)
			(end 0.12065 -0.2794)
			(stroke
				(width 0.1)
				(type default)
			)
			(layer "F.Fab")
		)
		(fp_line
			(start -0.12065 -0.305054)
			(end -0.12065 -0.2794)
			(stroke
				(width 0.1)
				(type default)
			)
			(layer "F.Fab")
		)
		(fp_line
			(start -0.67945 0.3048)
			(end -0.67945 -0.305054)
			(stroke
				(width 0.1)
				(type default)
			)
			(layer "F.Fab")
		)
		(fp_line
			(start -0.67945 -0.305054)
			(end -0.12065 -0.305054)
			(stroke
				(width 0.1)
				(type default)
			)
			(layer "F.Fab")
		)
		(pad "1" smd circle
			(at -0.40005 0 180)
			(size 0 0)
			(layers "F.Cu" "F.Mask" "F.Paste")
			(net "OCP_V3_2_AUX_PWR_EN_R2")
		)
		(pad "2" smd circle
			(at 0.40005 0 180)
			(size 0 0)
			(layers "F.Cu" "F.Mask" "F.Paste")
			(net "FM_OCP_V3_2_AUX_PWR_R_EN")
		)
	)
	(footprint ""
		(layer "F.Cu")
		(at 304.931572 -25.62225)
		(property "Reference" "U9"
			(at -1.8034 -1.819148 0)
			(unlocked yes)
			(layer "F.SilkS")
			(effects
				(font
					(size 0.7874 0.5842)
					(thickness 0.1524)
				)
				(justify left)
			)
		)
		(property "Value" ""
			(at 0 0 0)
			(layer "F.Fab")
			(effects
				(font
					(size 1.27 1.27)
				)
			)
		)
		(duplicate_pad_numbers_are_jumpers no)
		(fp_line
			(start -1.684274 -1.074928)
			(end -0.381 -1.074928)
			(stroke
				(width 0.1524)
				(type default)
			)
			(layer "F.SilkS")
		)
		(fp_line
			(start -1.684274 1.074928)
			(end -1.684274 -1.074928)
			(stroke
				(width 0.1524)
				(type default)
			)
			(layer "F.SilkS")
		)
		(fp_line
			(start -0.381 -1.074928)
			(end 0 -0.625094)
			(stroke
				(width 0.1524)
				(type default)
			)
			(layer "F.SilkS")
		)
		(fp_line
			(start 0 -0.625094)
			(end 0.381 -1.074928)
			(stroke
				(width 0.1524)
				(type default)
			)
			(layer "F.SilkS")
		)
		(fp_line
			(start 0.381 -1.074928)
			(end 1.684274 -1.074928)
			(stroke
				(width 0.1524)
				(type default)
			)
			(layer "F.SilkS")
		)
		(fp_line
			(start 1.684274 -1.074928)
			(end 1.684274 1.074928)
			(stroke
				(width 0.1524)
				(type default)
			)
			(layer "F.SilkS")
		)
		(fp_line
			(start 1.684274 1.074928)
			(end -1.684274 1.074928)
			(stroke
				(width 0.1524)
				(type default)
			)
			(layer "F.SilkS")
		)
		(fp_poly
			(pts
				(xy -2.637282 -0.903986) (xy -2.637282 -0.395986) (xy -1.875282 -0.649986)
			)
			(stroke
				(width 0)
				(type default)
			)
			(fill yes)
			(layer "F.SilkS")
		)
		(fp_line
			(start -0.700024 -1.074928)
			(end -0.700024 1.074928)
			(stroke
				(width 0.1)
				(type default)
			)
			(layer "F.Fab")
		)
		(fp_line
			(start -0.700024 1.074928)
			(end 0.700024 1.074928)
			(stroke
				(width 0.1)
				(type default)
			)
			(layer "F.Fab")
		)
		(fp_line
			(start 0.700024 -1.074928)
			(end -0.700024 -1.074928)
			(stroke
				(width 0.1)
				(type default)
			)
			(layer "F.Fab")
		)
		(fp_line
			(start 0.700024 1.074928)
			(end 0.700024 -1.074928)
			(stroke
				(width 0.1)
				(type default)
			)
			(layer "F.Fab")
		)
		(fp_poly
			(pts
				(xy -2.637282 -0.903986) (xy -2.637282 -0.395986) (xy -1.875282 -0.649986)
			)
			(stroke
				(width 0)
				(type default)
			)
			(fill yes)
			(layer "F.Fab")
		)
		(pad "1" smd rect
			(at -1.100074 -0.649986 270)
			(size 0.4064 0.9144)
			(layers "F.Cu" "F.Mask" "F.Paste")
			(net "P1V5_BAT_IN")
		)
		(pad "2" smd rect
			(at -1.100074 0 270)
			(size 0.4064 0.9144)
			(layers "F.Cu" "F.Mask" "F.Paste")
			(net "GND")
		)
		(pad "3" smd rect
			(at -1.100074 0.649986 270)
			(size 0.4064 0.9144)
			(layers "F.Cu" "F.Mask" "F.Paste")
			(net "BAT_LDO_EN")
		)
		(pad "4" smd rect
			(at 1.100074 0.649986 270)
			(size 0.4064 0.9144)
			(layers "F.Cu" "F.Mask" "F.Paste")
			(net "U9_NR")
		)
		(pad "5" smd rect
			(at 1.100074 -0.649986 270)
			(size 0.4064 0.9144)
			(layers "F.Cu" "F.Mask" "F.Paste")
			(net "P1V5_BAT_OUT")
		)
	)
	(footprint ""
		(layer "F.Cu")
		(at 402.214842 -403.603206 -90)
		(property "Reference" "R1079"
			(at 0 0 270)
			(layer "F.SilkS")
			(hide yes)
			(effects
				(font
					(size 1.27 1.27)
				)
			)
		)
		(property "Value" ""
			(at 0 0 270)
			(layer "F.Fab")
			(effects
				(font
					(size 1.27 1.27)
				)
			)
		)
		(duplicate_pad_numbers_are_jumpers no)
		(fp_line
			(start -0.32512 0.175006)
			(end -0.32512 -0.175006)
			(stroke
				(width 0.1)
				(type default)
			)
			(layer "F.Fab")
		)
		(fp_line
			(start 0.32512 0.175006)
			(end -0.32512 0.175006)
			(stroke
				(width 0.1)
				(type default)
			)
			(layer "F.Fab")
		)
		(fp_line
			(start -0.32512 -0.175006)
			(end 0.32512 -0.175006)
			(stroke
				(width 0.1)
				(type default)
			)
			(layer "F.Fab")
		)
		(fp_line
			(start 0.32512 -0.175006)
			(end 0.32512 0.175006)
			(stroke
				(width 0.1)
				(type default)
			)
			(layer "F.Fab")
		)
		(pad "1" smd rect
			(at -0.2667 0 270)
			(size 0.3048 0.381)
			(layers "F.Cu" "F.Mask" "F.Paste")
			(net "JTAG_TEST_MODE_RT_CPU0_P2")
		)
		(pad "2" smd rect
			(at 0.2667 0 90)
			(size 0.3048 0.381)
			(layers "F.Cu" "F.Mask" "F.Paste")
			(net "GND")
		)
	)
	(footprint ""
		(layer "F.Cu")
		(at 95.151702 -375.49963 -90)
		(property "Reference" "C720"
			(at 0 0 270)
			(layer "F.SilkS")
			(hide yes)
			(effects
				(font
					(size 1.27 1.27)
				)
			)
		)
		(property "Value" ""
			(at 0 0 270)
			(layer "F.Fab")
			(effects
				(font
					(size 1.27 1.27)
				)
			)
		)
		(duplicate_pad_numbers_are_jumpers no)
		(fp_line
			(start -0.299974 0.150114)
			(end -0.299974 -0.150114)
			(stroke
				(width 0.1)
				(type default)
			)
			(layer "F.Fab")
		)
		(fp_line
			(start 0.299974 0.150114)
			(end -0.299974 0.150114)
			(stroke
				(width 0.1)
				(type default)
			)
			(layer "F.Fab")
		)
		(fp_line
			(start -0.299974 -0.150114)
			(end 0.299974 -0.150114)
			(stroke
				(width 0.1)
				(type default)
			)
			(layer "F.Fab")
		)
		(fp_line
			(start 0.299974 -0.150114)
			(end 0.299974 0.150114)
			(stroke
				(width 0.1)
				(type default)
			)
			(layer "F.Fab")
		)
		(pad "1" smd rect
			(at -0.2667 0 270)
			(size 0.3048 0.381)
			(layers "F.Cu" "F.Mask" "F.Paste")
			(net "P5E_CPU1_P1_TX_C_DN<10>")
		)
		(pad "2" smd rect
			(at 0.2667 0 270)
			(size 0.3048 0.381)
			(layers "F.Cu" "F.Mask" "F.Paste")
			(net "P5E_CPU1_P1_TX_DN<10>")
		)
	)
	(footprint ""
		(layer "F.Cu")
		(at 108.4199 -395.769084 90)
		(property "Reference" "R6735"
			(at 0 0 90)
			(layer "F.SilkS")
			(hide yes)
			(effects
				(font
					(size 1.27 1.27)
				)
			)
		)
		(property "Value" ""
			(at 0 0 90)
			(layer "F.Fab")
			(effects
				(font
					(size 1.27 1.27)
				)
			)
		)
		(duplicate_pad_numbers_are_jumpers no)
		(fp_line
			(start 0.32512 -0.175006)
			(end 0.32512 0.175006)
			(stroke
				(width 0.1)
				(type default)
			)
			(layer "F.Fab")
		)
		(fp_line
			(start -0.32512 -0.175006)
			(end 0.32512 -0.175006)
			(stroke
				(width 0.1)
				(type default)
			)
			(layer "F.Fab")
		)
		(fp_line
			(start 0.32512 0.175006)
			(end -0.32512 0.175006)
			(stroke
				(width 0.1)
				(type default)
			)
			(layer "F.Fab")
		)
		(fp_line
			(start -0.32512 0.175006)
			(end -0.32512 -0.175006)
			(stroke
				(width 0.1)
				(type default)
			)
			(layer "F.Fab")
		)
		(pad "1" smd rect
			(at -0.2667 0 90)
			(size 0.3048 0.381)
			(layers "F.Cu" "F.Mask" "F.Paste")
			(net "P1V8_CPU1_RT_1D")
		)
		(pad "2" smd rect
			(at 0.2667 0 270)
			(size 0.3048 0.381)
			(layers "F.Cu" "F.Mask" "F.Paste")
			(net "SMB_RT_CPU1_P1_ROM_R_SDA")
		)
	)
)
